FILE_TYPE = CONNECTIVITY;
{Allegro Design Entry HDL 17.2-2016 S081 (4005846) 1/11/2022}
"PAGE_NUMBER" = 57;
0"NC";
1"GND\g";
2"GND\g";
3"GND\g";
4"GND\g";
5"GND\g";
6"GND\g";
7"GND\g";
%"GND_POWER"
"1","(-2025,3300)","0","standard","I1";
;
CDS_LIB"standard"
HDL_POWER"GND"
BODY_TYPE"PLUMBING"
VOLTAGE"0";
"GND"3;
%"HOLE"
"1","(2375,3575)","0","pure_quanta","I14";
;
PACK_TYPE"TH"
MATERIAL"EMPTY"
PART_NUMBER"DUMMY50"
NEEDS_NO_SIZE"TRUE"
CDS_LIB"pure_quanta"
LOCATION"H2B1"
$SEC"1"
CDS_SEC"1";
"1 \B"
$PN"1"0;
%"GND_POWER"
"1","(200,2700)","0","standard","I31";
;
VOLTAGE"0"
CDS_LIB"standard"
BODY_TYPE"PLUMBING"
HDL_POWER"GND";
"GND"2;
%"GND_POWER"
"1","(175,3275)","0","standard","I33";
;
VOLTAGE"0"
CDS_LIB"standard"
BODY_TYPE"PLUMBING"
HDL_POWER"GND";
"GND"1;
%"HOLE"
"1","(2375,3050)","0","pure_quanta","I34";
;
PART_NUMBER"DUMMY50"
PACK_TYPE"TH"
MATERIAL"EMPTY"
CDS_LIB"pure_quanta"
NEEDS_NO_SIZE"TRUE"
LOCATION"H2B2"
$SEC"1"
CDS_SEC"1";
"1 \B"
$PN"1"0;
%"HOLE"
"1","(-1675,3600)","0","pure_quanta","I35";
;
PACK_TYPE"TH"
MATERIAL"EMPTY"
PART_NUMBER"HOLE1211"
NEEDS_NO_SIZE"TRUE"
CDS_LIB"pure_quanta"
LOCATION"H5"
$SEC"1"
CDS_SEC"1";
"1 \B"
$PN"1"3;
%"HOLE"
"1","(-1650,2975)","0","pure_quanta","I36";
;
MATERIAL"EMPTY"
PART_NUMBER"HOLE1211"
PACK_TYPE"TH"
NEEDS_NO_SIZE"TRUE"
CDS_LIB"pure_quanta"
LOCATION"H9"
$SEC"1"
CDS_SEC"1";
"1 \B"
$PN"1"4;
%"GND_POWER"
"1","(-2000,2675)","0","standard","I37";
;
VOLTAGE"0"
CDS_LIB"standard"
BODY_TYPE"PLUMBING"
HDL_POWER"GND";
"GND"4;
%"HOLE"
"1","(-1625,1425)","0","pure_quanta","I38";
;
PACK_TYPE"TH"
MATERIAL"EMPTY"
PART_NUMBER"HOLE620"
CDS_LIB"pure_quanta"
NEEDS_NO_SIZE"TRUE"
$LOCATION"H3"
CDS_LOCATION"H3"
$SEC"1"
CDS_SEC"1";
"1 \B"
$PN"1"5;
%"GND_POWER"
"1","(-1975,1125)","0","standard","I39";
;
CDS_LIB"standard"
HDL_POWER"GND"
BODY_TYPE"PLUMBING"
VOLTAGE"0";
"GND"5;
%"HOLE"
"1","(-1625,550)","0","pure_quanta","I40";
;
PART_NUMBER"HOLE620"
MATERIAL"EMPTY"
PACK_TYPE"TH"
NEEDS_NO_SIZE"TRUE"
CDS_LIB"pure_quanta"
$LOCATION"H4"
CDS_LOCATION"H4"
$SEC"1"
CDS_SEC"1";
"1 \B"
$PN"1"6;
%"GND_POWER"
"1","(-1975,250)","0","standard","I41";
;
VOLTAGE"0"
BODY_TYPE"PLUMBING"
HDL_POWER"GND"
CDS_LIB"standard";
"GND"6;
%"GND_POWER"
"1","(150,1175)","0","standard","I43";
;
HDL_POWER"GND"
BODY_TYPE"PLUMBING"
VOLTAGE"0"
CDS_LIB"standard";
"GND"7;
%"HOLE"
"1","(525,650)","0","pure_quanta","I45";
;
PART_NUMBER"HOLE1247"
MATERIAL"EMPTY"
PACK_TYPE"TH"
CDS_LIB"pure_quanta"
NEEDS_NO_SIZE"TRUE"
$LOCATION"H2"
CDS_LOCATION"H2"
$SEC"1"
CDS_SEC"1";
"1 \B"
$PN"1"0;
%"HOLE"
"1","(500,1475)","0","pure_quanta","I49";
;
PACK_TYPE"TH"
PART_NUMBER"HOLE1248"
MATERIAL"EMPTY"
NEEDS_NO_SIZE"TRUE"
CDS_LIB"pure_quanta"
LOCATION"H1"
$SEC"1"
CDS_SEC"1";
"1 \B"
$PN"1"7;
%"HOLE"
"1","(525,3575)","0","pure_quanta","I50";
;
MATERIAL"EMPTY"
PART_NUMBER"TMP-C_HOLE8"
PACK_TYPE"TH"
NEEDS_NO_SIZE"TRUE"
CDS_LIB"pure_quanta"
LOCATION"H6"
$SEC"1"
CDS_SEC"1";
"1 \B"
$PN"1"1;
%"HOLE"
"1","(550,3000)","0","pure_quanta","I51";
;
MATERIAL"EMPTY"
PART_NUMBER"TMP-C_HOLE8"
PACK_TYPE"TH"
CDS_LIB"pure_quanta"
NEEDS_NO_SIZE"TRUE"
LOCATION"H7"
$SEC"1"
CDS_SEC"1";
"1 \B"
$PN"1"2;
END.
